(kicad_pcb
	(version 20241229)
	(generator "pcbnew")
	(generator_version "9.0")
	(general
		(thickness 1.62)
		(legacy_teardrops no)
	)
	(paper "A3")
	(title_block
		(title "COM Express 7 Baseboard")
		(date "2025-02-04")
		(rev "1.1.2")
		(company "Antmicro Ltd")
		(comment 1 "www.antmicro.com")
		(comment 9 "footprints 39-43 of 802")
	)
	(layers
		(0 "F.Cu" signal)
		(4 "In1.Cu" signal)
		(6 "In2.Cu" signal)
		(8 "In3.Cu" signal)
		(10 "In4.Cu" signal)
		(12 "In5.Cu" signal)
		(14 "In6.Cu" signal)
		(2 "B.Cu" signal)
		(9 "F.Adhes" user "F.Adhesive")
		(11 "B.Adhes" user "B.Adhesive")
		(13 "F.Paste" user)
		(15 "B.Paste" user)
		(5 "F.SilkS" user "F.Silkscreen")
		(7 "B.SilkS" user "B.Silkscreen")
		(1 "F.Mask" user)
		(3 "B.Mask" user)
		(17 "Dwgs.User" user "User.Drawings")
		(19 "Cmts.User" user "User.Comments")
		(21 "Eco1.User" user "User.Eco1")
		(23 "Eco2.User" user "User.Eco2")
		(25 "Edge.Cuts" user)
		(27 "Margin" user)
		(31 "F.CrtYd" user "F.Courtyard")
		(29 "B.CrtYd" user "B.Courtyard")
		(35 "F.Fab" user)
		(33 "B.Fab" user)
	)
	(footprint "antmicro-footprints:R_0402_1005Metric"
		(layer "F.Cu")
		(at 309.174999 104.35 -90)
		(descr "Resistor SMD 0402")
		(tags "resistor SMD 0402")
		(property "Reference" "R100"
			(at -0.54 0.224999 45)
			(layer "F.SilkS")
			(effects
				(font
					(size 0.7 0.7)
					(thickness 0.15)
				)
				(justify right bottom)
			)
		)
		(property "Value" "R_15k_0402"
			(at -1.011843 1.772047 90)
			(layer "F.Fab")
			(effects
				(font
					(size 0.7 0.7)
					(thickness 0.15)
				)
				(justify right bottom)
			)
		)
		(property "Datasheet" "https://www.bourns.com/docs/product-datasheets/cr.pdf"
			(at 0 0 270)
			(layer "F.Fab")
			(hide yes)
			(effects
				(font
					(size 1.27 1.27)
					(thickness 0.15)
				)
			)
		)
		(property "Author" "Antmicro"
			(at 204.824999 413.524999 0)
			(layer "F.Fab")
			(hide yes)
			(effects
				(font
					(size 1 1)
					(thickness 0.15)
				)
			)
		)
		(property "License" "Apache-2.0"
			(at 204.824999 413.524999 0)
			(layer "F.Fab")
			(hide yes)
			(effects
				(font
					(size 1 1)
					(thickness 0.15)
				)
			)
		)
		(property "MPN" "CR0402-FX-1502GLF"
			(at 204.824999 413.524999 0)
			(layer "F.Fab")
			(hide yes)
			(effects
				(font
					(size 1 1)
					(thickness 0.15)
				)
			)
		)
		(property "Manufacturer" "Bourns"
			(at 204.824999 413.524999 0)
			(layer "F.Fab")
			(hide yes)
			(effects
				(font
					(size 1 1)
					(thickness 0.15)
				)
			)
		)
		(property "Public" "False"
			(at 204.824999 413.524999 0)
			(layer "F.Fab")
			(hide yes)
			(effects
				(font
					(size 1 1)
					(thickness 0.15)
				)
			)
		)
		(property "Tolerance" "1%"
			(at 204.824999 413.524999 0)
			(layer "F.Fab")
			(hide yes)
			(effects
				(font
					(size 1 1)
					(thickness 0.15)
				)
			)
		)
		(property "Val" "15k"
			(at 204.824999 413.524999 0)
			(layer "F.Fab")
			(hide yes)
			(effects
				(font
					(size 1 1)
					(thickness 0.15)
				)
			)
		)
		(sheetname "Power")
		(sheetfile "power.kicad_sch")
		(attr smd)
		(fp_rect
			(start -0.925 -0.47)
			(end 0.925 0.47)
			(stroke
				(width 0.05)
				(type default)
			)
			(fill no)
			(layer "F.CrtYd")
		)
		(fp_rect
			(start -0.5 -0.25)
			(end 0.5 0.25)
			(stroke
				(width 0.15)
				(type solid)
			)
			(fill no)
			(layer "F.Fab")
		)
		(pad "1" smd roundrect
			(at -0.48 0 270)
			(size 0.59 0.64)
			(layers "F.Cu" "F.Mask" "F.Paste")
			(roundrect_rratio 0.25)
			(net 1 "GND")
			(pintype "passive")
			(teardrops
				(best_length_ratio 0.2)
				(max_length 1)
				(best_width_ratio 0.9)
				(max_width 2)
				(curved_edges yes)
				(filter_ratio 0.9)
				(enabled yes)
				(allow_two_segments yes)
				(prefer_zone_connections yes)
			)
		)
		(pad "2" smd roundrect
			(at 0.48 0 270)
			(size 0.59 0.64)
			(layers "F.Cu" "F.Mask" "F.Paste")
			(roundrect_rratio 0.25)
			(net 581 "Net-(U19-FB)")
			(pintype "passive")
			(teardrops
				(best_length_ratio 0.2)
				(max_length 1)
				(best_width_ratio 0.9)
				(max_width 2)
				(curved_edges yes)
				(filter_ratio 0.9)
				(enabled yes)
				(allow_two_segments yes)
				(prefer_zone_connections yes)
			)
		)
	)
	(footprint "antmicro-footprints:Trans_Eth_4.7x3.3mm"
		(layer "F.Cu")
		(at 130.63 104.35)
		(property "Reference" "T6"
			(at 4.92 0.15 0)
			(unlocked yes)
			(layer "F.SilkS")
			(effects
				(font
					(size 0.7 0.7)
					(thickness 0.15)
				)
				(justify left bottom)
			)
		)
		(property "Value" "Trans_SM453229-381N7Y"
			(at 2.39 11.52 0)
			(unlocked yes)
			(layer "F.Fab")
			(effects
				(font
					(size 0.7 0.7)
					(thickness 0.15)
				)
				(justify left bottom)
			)
		)
		(property "Datasheet" "https://eu.mouser.com/datasheet/2/54/bourns_02132019_SM453229-381N7Y_datasheet-1532071.pdf"
			(at 0 0 0)
			(layer "F.Fab")
			(hide yes)
			(effects
				(font
					(size 1.27 1.27)
					(thickness 0.15)
				)
			)
		)
		(property "Author" "Antmicro"
			(at 0 0 0)
			(layer "F.Fab")
			(hide yes)
			(effects
				(font
					(size 1 1)
					(thickness 0.15)
				)
			)
		)
		(property "License" "Apache-2.0"
			(at 0 0 0)
			(layer "F.Fab")
			(hide yes)
			(effects
				(font
					(size 1 1)
					(thickness 0.15)
				)
			)
		)
		(property "MPN" "SM453229-381N7Y"
			(at 0 0 0)
			(layer "F.Fab")
			(hide yes)
			(effects
				(font
					(size 1 1)
					(thickness 0.15)
				)
			)
		)
		(property "Manufacturer" "Bourns"
			(at 0 0 0)
			(layer "F.Fab")
			(hide yes)
			(effects
				(font
					(size 1 1)
					(thickness 0.15)
				)
			)
		)
		(sheetname "2xUSB3.0+RJ45")
		(sheetfile "usb3+rj45.kicad_sch")
		(attr smd)
		(fp_line
			(start -0.15 -0.6)
			(end -0.15 0.55)
			(stroke
				(width 0.1)
				(type default)
			)
			(layer "F.SilkS")
		)
		(fp_line
			(start 3.4 -1.6)
			(end 1 -1.6)
			(stroke
				(width 0.1)
				(type default)
			)
			(layer "F.SilkS")
		)
		(fp_line
			(start 3.4 1.7)
			(end 1 1.7)
			(stroke
				(width 0.1)
				(type default)
			)
			(layer "F.SilkS")
		)
		(fp_line
			(start 4.55 -0.25)
			(end 4.55 0.9)
			(stroke
				(width 0.1)
				(type default)
			)
			(layer "F.SilkS")
		)
		(fp_circle
			(center 0.1 2.3)
			(end 0.15 2.3)
			(stroke
				(width 0.15)
				(type solid)
			)
			(fill yes)
			(layer "F.SilkS")
		)
		(fp_rect
			(start -0.6 -1.9)
			(end 4.94 1.9)
			(stroke
				(width 0.05)
				(type solid)
			)
			(fill no)
			(layer "F.CrtYd")
		)
		(pad "1" smd roundrect
			(at 0.17 1.5)
			(size 0.96 0.27)
			(layers "F.Cu" "F.Mask" "F.Paste")
			(roundrect_rratio 0.25)
			(net 691 "/2xUSB3.0+RJ45/DB_FL+")
			(pinfunction "1")
			(pintype "passive")
			(teardrops
				(best_length_ratio 0.2)
				(max_length 1)
				(best_width_ratio 0.9)
				(max_width 2)
				(curved_edges yes)
				(filter_ratio 0.9)
				(enabled yes)
				(allow_two_segments yes)
				(prefer_zone_connections yes)
			)
		)
		(pad "2" smd roundrect
			(at 0.115 0.855)
			(size 0.85 0.28)
			(layers "F.Cu" "F.Mask" "F.Paste")
			(roundrect_rratio 0.25)
			(net 692 "/2xUSB3.0+RJ45/DB_FL-")
			(pinfunction "2")
			(pintype "passive")
			(teardrops
				(best_length_ratio 0.2)
				(max_length 1)
				(best_width_ratio 0.9)
				(max_width 2)
				(curved_edges yes)
				(filter_ratio 0.9)
				(enabled yes)
				(allow_two_segments yes)
				(prefer_zone_connections yes)
			)
		)
		(pad "3" smd roundrect
			(at 0.14 -1.21)
			(size 0.9 0.77)
			(layers "F.Cu" "F.Mask" "F.Paste")
			(roundrect_rratio 0.1)
			(net 51 "Net-(C13-Pad1)")
			(pinfunction "3")
			(pintype "passive")
			(teardrops
				(best_length_ratio 0.2)
				(max_length 1)
				(best_width_ratio 0.9)
				(max_width 2)
				(curved_edges yes)
				(filter_ratio 0.9)
				(enabled yes)
				(allow_two_segments yes)
				(prefer_zone_connections yes)
			)
		)
		(pad "5" smd roundrect
			(at 4.215 1.385)
			(size 0.95 0.5)
			(layers "F.Cu" "F.Mask" "F.Paste")
			(roundrect_rratio 0.1)
			(net 550 "Net-(R15-Pad2)")
			(pinfunction "5")
			(pintype "passive")
			(teardrops
				(best_length_ratio 0.2)
				(max_length 1)
				(best_width_ratio 0.9)
				(max_width 2)
				(curved_edges yes)
				(filter_ratio 0.9)
				(enabled yes)
				(allow_two_segments yes)
				(prefer_zone_connections yes)
			)
		)
		(pad "6" smd roundrect
			(at 4.265 -0.645)
			(size 0.85 0.34)
			(layers "F.Cu" "F.Mask" "F.Paste")
			(roundrect_rratio 0.1)
			(net 293 "/2xUSB3.0+RJ45/GbE.MDI1+")
			(pinfunction "6")
			(pintype "passive")
			(teardrops
				(best_length_ratio 0.2)
				(max_length 1)
				(best_width_ratio 0.9)
				(max_width 2)
				(curved_edges yes)
				(filter_ratio 0.9)
				(enabled yes)
				(allow_two_segments yes)
				(prefer_zone_connections yes)
			)
		)
		(pad "7" smd roundrect
			(at 4.205 -1.43)
			(size 0.97 0.33)
			(layers "F.Cu" "F.Mask" "F.Paste")
			(roundrect_rratio 0.1)
			(net 292 "/2xUSB3.0+RJ45/GbE.MDI1-")
			(pinfunction "7")
			(pintype "passive")
			(teardrops
				(best_length_ratio 0.2)
				(max_length 1)
				(best_width_ratio 0.9)
				(max_width 2)
				(curved_edges yes)
				(filter_ratio 0.9)
				(enabled yes)
				(allow_two_segments yes)
				(prefer_zone_connections yes)
			)
		)
	)
	(footprint "antmicro-footprints:Trans_Eth_4.7x3.3mm"
		(layer "F.Cu")
		(at 130.63 108.27)
		(property "Reference" "T7"
			(at 4.92 0.3 0)
			(unlocked yes)
			(layer "F.SilkS")
			(effects
				(font
					(size 0.7 0.7)
					(thickness 0.15)
				)
				(justify left bottom)
			)
		)
		(property "Value" "Trans_SM453229-381N7Y"
			(at 2.39 11.52 0)
			(unlocked yes)
			(layer "F.Fab")
			(effects
				(font
					(size 0.7 0.7)
					(thickness 0.15)
				)
				(justify left bottom)
			)
		)
		(property "Datasheet" "https://eu.mouser.com/datasheet/2/54/bourns_02132019_SM453229-381N7Y_datasheet-1532071.pdf"
			(at 0 0 0)
			(layer "F.Fab")
			(hide yes)
			(effects
				(font
					(size 1.27 1.27)
					(thickness 0.15)
				)
			)
		)
		(property "Author" "Antmicro"
			(at 0 0 0)
			(layer "F.Fab")
			(hide yes)
			(effects
				(font
					(size 1 1)
					(thickness 0.15)
				)
			)
		)
		(property "License" "Apache-2.0"
			(at 0 0 0)
			(layer "F.Fab")
			(hide yes)
			(effects
				(font
					(size 1 1)
					(thickness 0.15)
				)
			)
		)
		(property "MPN" "SM453229-381N7Y"
			(at 0 0 0)
			(layer "F.Fab")
			(hide yes)
			(effects
				(font
					(size 1 1)
					(thickness 0.15)
				)
			)
		)
		(property "Manufacturer" "Bourns"
			(at 0 0 0)
			(layer "F.Fab")
			(hide yes)
			(effects
				(font
					(size 1 1)
					(thickness 0.15)
				)
			)
		)
		(sheetname "2xUSB3.0+RJ45")
		(sheetfile "usb3+rj45.kicad_sch")
		(attr smd)
		(fp_line
			(start -0.15 -0.6)
			(end -0.15 0.55)
			(stroke
				(width 0.1)
				(type default)
			)
			(layer "F.SilkS")
		)
		(fp_line
			(start 3.4 -1.6)
			(end 1 -1.6)
			(stroke
				(width 0.1)
				(type default)
			)
			(layer "F.SilkS")
		)
		(fp_line
			(start 3.4 1.7)
			(end 1 1.7)
			(stroke
				(width 0.1)
				(type default)
			)
			(layer "F.SilkS")
		)
		(fp_line
			(start 4.55 -0.25)
			(end 4.55 0.9)
			(stroke
				(width 0.1)
				(type default)
			)
			(layer "F.SilkS")
		)
		(fp_circle
			(center 0.1 2.3)
			(end 0.15 2.3)
			(stroke
				(width 0.15)
				(type solid)
			)
			(fill yes)
			(layer "F.SilkS")
		)
		(fp_rect
			(start -0.6 -1.9)
			(end 4.94 1.9)
			(stroke
				(width 0.05)
				(type solid)
			)
			(fill no)
			(layer "F.CrtYd")
		)
		(pad "1" smd roundrect
			(at 0.17 1.5)
			(size 0.96 0.27)
			(layers "F.Cu" "F.Mask" "F.Paste")
			(roundrect_rratio 0.25)
			(net 693 "/2xUSB3.0+RJ45/DC_FL+")
			(pinfunction "1")
			(pintype "passive")
			(teardrops
				(best_length_ratio 0.2)
				(max_length 1)
				(best_width_ratio 0.9)
				(max_width 2)
				(curved_edges yes)
				(filter_ratio 0.9)
				(enabled yes)
				(allow_two_segments yes)
				(prefer_zone_connections yes)
			)
		)
		(pad "2" smd roundrect
			(at 0.115 0.855)
			(size 0.85 0.28)
			(layers "F.Cu" "F.Mask" "F.Paste")
			(roundrect_rratio 0.25)
			(net 694 "/2xUSB3.0+RJ45/DC_FL-")
			(pinfunction "2")
			(pintype "passive")
			(teardrops
				(best_length_ratio 0.2)
				(max_length 1)
				(best_width_ratio 0.9)
				(max_width 2)
				(curved_edges yes)
				(filter_ratio 0.9)
				(enabled yes)
				(allow_two_segments yes)
				(prefer_zone_connections yes)
			)
		)
		(pad "3" smd roundrect
			(at 0.14 -1.21)
			(size 0.9 0.77)
			(layers "F.Cu" "F.Mask" "F.Paste")
			(roundrect_rratio 0.1)
			(net 51 "Net-(C13-Pad1)")
			(pinfunction "3")
			(pintype "passive")
			(teardrops
				(best_length_ratio 0.2)
				(max_length 1)
				(best_width_ratio 0.9)
				(max_width 2)
				(curved_edges yes)
				(filter_ratio 0.9)
				(enabled yes)
				(allow_two_segments yes)
				(prefer_zone_connections yes)
			)
		)
		(pad "5" smd roundrect
			(at 4.215 1.385)
			(size 0.95 0.5)
			(layers "F.Cu" "F.Mask" "F.Paste")
			(roundrect_rratio 0.1)
			(net 551 "Net-(R16-Pad2)")
			(pinfunction "5")
			(pintype "passive")
			(teardrops
				(best_length_ratio 0.2)
				(max_length 1)
				(best_width_ratio 0.9)
				(max_width 2)
				(curved_edges yes)
				(filter_ratio 0.9)
				(enabled yes)
				(allow_two_segments yes)
				(prefer_zone_connections yes)
			)
		)
		(pad "6" smd roundrect
			(at 4.265 -0.645)
			(size 0.85 0.34)
			(layers "F.Cu" "F.Mask" "F.Paste")
			(roundrect_rratio 0.1)
			(net 290 "/2xUSB3.0+RJ45/GbE.MDI2+")
			(pinfunction "6")
			(pintype "passive")
			(teardrops
				(best_length_ratio 0.2)
				(max_length 1)
				(best_width_ratio 0.9)
				(max_width 2)
				(curved_edges yes)
				(filter_ratio 0.9)
				(enabled yes)
				(allow_two_segments yes)
				(prefer_zone_connections yes)
			)
		)
		(pad "7" smd roundrect
			(at 4.205 -1.43)
			(size 0.97 0.33)
			(layers "F.Cu" "F.Mask" "F.Paste")
			(roundrect_rratio 0.1)
			(net 289 "/2xUSB3.0+RJ45/GbE.MDI2-")
			(pinfunction "7")
			(pintype "passive")
			(teardrops
				(best_length_ratio 0.2)
				(max_length 1)
				(best_width_ratio 0.9)
				(max_width 2)
				(curved_edges yes)
				(filter_ratio 0.9)
				(enabled yes)
				(allow_two_segments yes)
				(prefer_zone_connections yes)
			)
		)
	)
	(footprint "antmicro-footprints:TP_SMD_0.75mm"
		(layer "F.Cu")
		(at 118.234999 76.15 90)
		(property "Reference" "TP10"
			(at 4.54 6.315001 0)
			(layer "F.SilkS")
			(effects
				(font
					(size 0.7 0.7)
					(thickness 0.15)
				)
				(justify left bottom)
			)
		)
		(property "Value" "TP_0.75mm_SMD"
			(at 0 1.2 90)
			(layer "F.Fab")
			(effects
				(font
					(size 0.7 0.7)
					(thickness 0.15)
				)
				(justify left bottom)
			)
		)
		(property "Author" "Antmicro"
			(at 194.384999 -42.084999 0)
			(layer "F.Fab")
			(hide yes)
			(effects
				(font
					(size 1 1)
					(thickness 0.15)
				)
			)
		)
		(property "License" "Apache-2.0"
			(at 194.384999 -42.084999 0)
			(layer "F.Fab")
			(hide yes)
			(effects
				(font
					(size 1 1)
					(thickness 0.15)
				)
			)
		)
		(property "MPN" ""
			(at 194.384999 -42.084999 0)
			(layer "F.Fab")
			(hide yes)
			(effects
				(font
					(size 1 1)
					(thickness 0.15)
				)
			)
		)
		(property "Manufacturer" ""
			(at 194.384999 -42.084999 0)
			(layer "F.Fab")
			(hide yes)
			(effects
				(font
					(size 1 1)
					(thickness 0.15)
				)
			)
		)
		(property "Public" "False"
			(at 194.384999 -42.084999 0)
			(layer "F.Fab")
			(hide yes)
			(effects
				(font
					(size 1 1)
					(thickness 0.15)
				)
			)
		)
		(sheetname "USB-C console")
		(sheetfile "usb-c_console.kicad_sch")
		(attr exclude_from_pos_files exclude_from_bom)
		(fp_circle
			(center 0 0)
			(end 0.475 0)
			(stroke
				(width 0.05)
				(type default)
			)
			(fill no)
			(layer "F.CrtYd")
		)
		(pad "1" smd circle
			(at 0 0 90)
			(size 0.75 0.75)
			(layers "F.Cu" "F.Mask")
			(net 702 "/USB-C console/FTDI_CBUS3")
			(pinfunction "1")
			(pintype "passive")
			(teardrops
				(best_length_ratio 0.4)
				(max_length 1)
				(best_width_ratio 0.9)
				(max_width 2)
				(curved_edges yes)
				(filter_ratio 0.9)
				(enabled yes)
				(allow_two_segments yes)
				(prefer_zone_connections yes)
			)
		)
	)
	(footprint "antmicro-footprints:R_0402_1005Metric"
		(layer "F.Cu")
		(at 186.70861 77.152163 90)
		(descr "Resistor SMD 0402")
		(tags "resistor SMD 0402")
		(property "Reference" "R324"
			(at -1.9 -0.5 90)
			(layer "F.SilkS")
			(effects
				(font
					(size 0.7 0.7)
					(thickness 0.15)
				)
				(justify left bottom)
			)
		)
		(property "Value" "R_2k2_0402"
			(at -1.011843 1.772047 90)
			(layer "F.Fab")
			(effects
				(font
					(size 0.7 0.7)
					(thickness 0.15)
				)
				(justify left bottom)
			)
		)
		(property "Datasheet" "https://www.bourns.com/docs/product-datasheets/cr.pdf"
			(at 0 0 90)
			(layer "F.Fab")
			(hide yes)
			(effects
				(font
					(size 1.27 1.27)
					(thickness 0.15)
				)
			)
		)
		(property "Author" "Antmicro"
			(at 263.860773 -109.556447 0)
			(layer "F.Fab")
			(hide yes)
			(effects
				(font
					(size 1 1)
					(thickness 0.15)
				)
			)
		)
		(property "License" "Apache-2.0"
			(at 263.860773 -109.556447 0)
			(layer "F.Fab")
			(hide yes)
			(effects
				(font
					(size 1 1)
					(thickness 0.15)
				)
			)
		)
		(property "MPN" "CR0402-FX-2201GLF"
			(at 263.860773 -109.556447 0)
			(layer "F.Fab")
			(hide yes)
			(effects
				(font
					(size 1 1)
					(thickness 0.15)
				)
			)
		)
		(property "Manufacturer" "Bourns"
			(at 263.860773 -109.556447 0)
			(layer "F.Fab")
			(hide yes)
			(effects
				(font
					(size 1 1)
					(thickness 0.15)
				)
			)
		)
		(property "Tolerance" "1%"
			(at 263.860773 -109.556447 0)
			(layer "F.Fab")
			(hide yes)
			(effects
				(font
					(size 1 1)
					(thickness 0.15)
				)
			)
		)
		(property "Val" "2k2"
			(at 263.860773 -109.556447 0)
			(layer "F.Fab")
			(hide yes)
			(effects
				(font
					(size 1 1)
					(thickness 0.15)
				)
			)
		)
		(sheetname "Power")
		(sheetfile "power.kicad_sch")
		(attr smd)
		(fp_rect
			(start -0.925 -0.47)
			(end 0.925 0.47)
			(stroke
				(width 0.05)
				(type default)
			)
			(fill no)
			(layer "F.CrtYd")
		)
		(fp_rect
			(start -0.5 -0.25)
			(end 0.5 0.25)
			(stroke
				(width 0.15)
				(type solid)
			)
			(fill no)
			(layer "F.Fab")
		)
		(pad "1" smd roundrect
			(at -0.48 0 90)
			(size 0.59 0.64)
			(layers "F.Cu" "F.Mask" "F.Paste")
			(roundrect_rratio 0.25)
			(net 1 "GND")
			(pintype "passive")
			(teardrops
				(best_length_ratio 0.2)
				(max_length 1)
				(best_width_ratio 0.9)
				(max_width 2)
				(curved_edges yes)
				(filter_ratio 0.9)
				(enabled yes)
				(allow_two_segments yes)
				(prefer_zone_connections yes)
			)
		)
		(pad "2" smd roundrect
			(at 0.48 0 90)
			(size 0.59 0.64)
			(layers "F.Cu" "F.Mask" "F.Paste")
			(roundrect_rratio 0.25)
			(net 983 "Net-(D31-C)")
			(pintype "passive")
			(teardrops
				(best_length_ratio 0.2)
				(max_length 1)
				(best_width_ratio 0.9)
				(max_width 2)
				(curved_edges yes)
				(filter_ratio 0.9)
				(enabled yes)
				(allow_two_segments yes)
				(prefer_zone_connections yes)
			)
		)
	)
)
